(kicad_pcb
	(version 20241229)
	(generator "pcbnew")
	(generator_version "9.0")
	(general
		(thickness 1.61)
		(legacy_teardrops no)
	)
	(paper "A3")
	(title_block
		(title "SO-DIMM DDR5 Tester")
		(date "2025-11-26")
		(rev "1.3.0")
		(comment 9 "footprints 43-45 of 627")
	)
	(layers
		(0 "F.Cu" signal)
		(4 "In1.Cu" power)
		(6 "In2.Cu" mixed)
		(8 "In3.Cu" power)
		(10 "In4.Cu" mixed)
		(12 "In5.Cu" power)
		(14 "In6.Cu" mixed)
		(16 "In7.Cu" power)
		(18 "In8.Cu" power)
		(20 "In9.Cu" mixed)
		(22 "In10.Cu" power)
		(2 "B.Cu" signal)
		(9 "F.Adhes" user "F.Adhesive")
		(11 "B.Adhes" user "B.Adhesive")
		(13 "F.Paste" user)
		(15 "B.Paste" user)
		(5 "F.SilkS" user "F.Silkscreen")
		(7 "B.SilkS" user "B.Silkscreen")
		(1 "F.Mask" user)
		(3 "B.Mask" user)
		(17 "Dwgs.User" user "User.Drawings")
		(19 "Cmts.User" user "User.Comments")
		(21 "Eco1.User" user "User.Eco1")
		(23 "Eco2.User" user "User.Eco2")
		(25 "Edge.Cuts" user)
		(27 "Margin" user)
		(31 "F.CrtYd" user "F.Courtyard")
		(29 "B.CrtYd" user "B.Courtyard")
		(35 "F.Fab" user)
		(33 "B.Fab" user)
	)
	(footprint "antmicro-footprints:QFN-48-1EP_7x7x0.9mm_P0.5mm_EP3.5x3.5mm"
		(layer "F.Cu")
		(at 93.550501 154.786 -90)
		(property "Reference" "U15"
			(at 5.114 -2.249499 0)
			(layer "F.SilkS")
			(effects
				(font
					(size 0.7 0.7)
					(thickness 0.15)
				)
				(justify left bottom)
			)
		)
		(property "Value" "KSZ9031RNXCA"
			(at 0 5.1 270)
			(layer "F.Fab")
			(hide yes)
			(effects
				(font
					(size 0.7 0.7)
					(thickness 0.15)
				)
				(justify left bottom)
			)
		)
		(property "Datasheet" "http://ww1.microchip.com/downloads/en/DeviceDoc/00002117F.pdf"
			(at 0 0 270)
			(layer "F.Fab")
			(hide yes)
			(effects
				(font
					(size 1.27 1.27)
					(thickness 0.15)
				)
			)
		)
		(property "Author" "Antmicro"
			(at -61.235499 248.336501 0)
			(layer "F.Fab")
			(hide yes)
			(effects
				(font
					(size 1 1)
					(thickness 0.15)
				)
			)
		)
		(property "License" "Apache-2.0"
			(at -61.235499 248.336501 0)
			(layer "F.Fab")
			(hide yes)
			(effects
				(font
					(size 1 1)
					(thickness 0.15)
				)
			)
		)
		(property "MPN" "KSZ9031RNXCA"
			(at -61.235499 248.336501 0)
			(layer "F.Fab")
			(hide yes)
			(effects
				(font
					(size 1 1)
					(thickness 0.15)
				)
			)
		)
		(property "Manufacturer" "Microchip Technology"
			(at -61.235499 248.336501 0)
			(layer "F.Fab")
			(hide yes)
			(effects
				(font
					(size 1 1)
					(thickness 0.15)
				)
			)
		)
		(sheetname "/Ethernet/")
		(sheetfile "ethernet.kicad_sch")
		(attr smd)
		(fp_line
			(start -3.65 3.648)
			(end -3.65 3.249)
			(stroke
				(width 0.15)
				(type solid)
			)
			(layer "F.SilkS")
		)
		(fp_line
			(start -3.25 3.648)
			(end -3.65 3.648)
			(stroke
				(width 0.15)
				(type solid)
			)
			(layer "F.SilkS")
		)
		(fp_line
			(start 3.249 3.648)
			(end 3.648 3.648)
			(stroke
				(width 0.15)
				(type solid)
			)
			(layer "F.SilkS")
		)
		(fp_line
			(start 3.648 3.648)
			(end 3.648 3.249)
			(stroke
				(width 0.15)
				(type solid)
			)
			(layer "F.SilkS")
		)
		(fp_line
			(start -3.65 -3.3)
			(end -3.65 -3.65)
			(stroke
				(width 0.15)
				(type solid)
			)
			(layer "F.SilkS")
		)
		(fp_line
			(start -3.3 -3.65)
			(end -3.65 -3.65)
			(stroke
				(width 0.15)
				(type solid)
			)
			(layer "F.SilkS")
		)
		(fp_line
			(start 3.249 -3.65)
			(end 3.648 -3.65)
			(stroke
				(width 0.15)
				(type solid)
			)
			(layer "F.SilkS")
		)
		(fp_line
			(start 3.648 -3.65)
			(end 3.648 -3.25)
			(stroke
				(width 0.15)
				(type solid)
			)
			(layer "F.SilkS")
		)
		(fp_circle
			(center -3.7 -3.05)
			(end -3.65 -3.05)
			(stroke
				(width 0.15)
				(type solid)
			)
			(fill yes)
			(layer "F.SilkS")
		)
		(fp_rect
			(start -4.15 -4.15)
			(end 4.15 4.15)
			(stroke
				(width 0.05)
				(type solid)
			)
			(fill no)
			(layer "F.CrtYd")
		)
		(fp_line
			(start -3.5 3.499)
			(end 3.499 3.499)
			(stroke
				(width 0.15)
				(type solid)
			)
			(layer "F.Fab")
		)
		(fp_line
			(start 3.499 3.499)
			(end 3.499 -3.5)
			(stroke
				(width 0.15)
				(type solid)
			)
			(layer "F.Fab")
		)
		(fp_line
			(start -3.5 -2.5)
			(end -3.5 3.499)
			(stroke
				(width 0.15)
				(type solid)
			)
			(layer "F.Fab")
		)
		(fp_line
			(start -2.5 -3.5)
			(end -3.5 -2.5)
			(stroke
				(width 0.15)
				(type solid)
			)
			(layer "F.Fab")
		)
		(fp_line
			(start 3.499 -3.5)
			(end -2.5 -3.5)
			(stroke
				(width 0.15)
				(type solid)
			)
			(layer "F.Fab")
		)
		(pad "1" smd oval
			(at -3.5 -2.75)
			(size 0.3 0.9)
			(layers "F.Cu" "F.Mask" "F.Paste")
			(net 134 "/Ethernet/AVDDH")
			(pinfunction "AVDDH")
			(pintype "power_in")
		)
		(pad "2" smd oval
			(at -3.5 -2.25)
			(size 0.3 0.9)
			(layers "F.Cu" "F.Mask" "F.Paste")
			(net 125 "/Ethernet/ETH1_P")
			(pinfunction "TXRXP_A")
			(pintype "bidirectional")
		)
		(pad "3" smd oval
			(at -3.5 -1.75)
			(size 0.3 0.9)
			(layers "F.Cu" "F.Mask" "F.Paste")
			(net 128 "/Ethernet/ETH1_N")
			(pinfunction "TXRXM_A")
			(pintype "bidirectional")
		)
		(pad "4" smd oval
			(at -3.5 -1.25)
			(size 0.3 0.9)
			(layers "F.Cu" "F.Mask" "F.Paste")
			(net 132 "/Ethernet/AVDDL")
			(pinfunction "AVDDL")
			(pintype "power_in")
		)
		(pad "5" smd oval
			(at -3.5 -0.75)
			(size 0.3 0.9)
			(layers "F.Cu" "F.Mask" "F.Paste")
			(net 124 "/Ethernet/ETH2_P")
			(pinfunction "TXRXP_B")
			(pintype "bidirectional")
		)
		(pad "6" smd oval
			(at -3.5 -0.25)
			(size 0.3 0.9)
			(layers "F.Cu" "F.Mask" "F.Paste")
			(net 127 "/Ethernet/ETH2_N")
			(pinfunction "TXRXM_B")
			(pintype "bidirectional")
		)
		(pad "7" smd oval
			(at -3.5 0.248)
			(size 0.3 0.9)
			(layers "F.Cu" "F.Mask" "F.Paste")
			(net 123 "/Ethernet/ETH3_P")
			(pinfunction "TXRXP_C")
			(pintype "bidirectional")
		)
		(pad "8" smd oval
			(at -3.5 0.748)
			(size 0.3 0.9)
			(layers "F.Cu" "F.Mask" "F.Paste")
			(net 129 "/Ethernet/ETH3_N")
			(pinfunction "TXRXM_C")
			(pintype "bidirectional")
		)
		(pad "9" smd oval
			(at -3.5 1.249)
			(size 0.3 0.9)
			(layers "F.Cu" "F.Mask" "F.Paste")
			(net 132 "/Ethernet/AVDDL")
			(pinfunction "AVDDL")
			(pintype "passive")
		)
		(pad "10" smd oval
			(at -3.5 1.749)
			(size 0.3 0.9)
			(layers "F.Cu" "F.Mask" "F.Paste")
			(net 126 "/Ethernet/ETH4_P")
			(pinfunction "TXRXP_D")
			(pintype "bidirectional")
		)
		(pad "11" smd oval
			(at -3.5 2.249)
			(size 0.3 0.9)
			(layers "F.Cu" "F.Mask" "F.Paste")
			(net 130 "/Ethernet/ETH4_N")
			(pinfunction "TXRXM_D")
			(pintype "bidirectional")
		)
		(pad "12" smd oval
			(at -3.5 2.749)
			(size 0.3 0.9)
			(layers "F.Cu" "F.Mask" "F.Paste")
			(net 134 "/Ethernet/AVDDH")
			(pinfunction "AVDDH")
			(pintype "passive")
		)
		(pad "13" smd oval
			(at -2.75 3.499 270)
			(size 0.3 0.9)
			(layers "F.Cu" "F.Mask" "F.Paste")
			(net 721 "unconnected-(U15-NC-Pad13)")
			(pinfunction "NC")
			(pintype "no_connect")
		)
		(pad "14" smd oval
			(at -2.25 3.499 270)
			(size 0.3 0.9)
			(layers "F.Cu" "F.Mask" "F.Paste")
			(net 199 "+1V2")
			(pinfunction "DVDDL")
			(pintype "power_in")
		)
		(pad "15" smd oval
			(at -1.75 3.499 270)
			(size 0.3 0.9)
			(layers "F.Cu" "F.Mask" "F.Paste")
			(net 602 "/Ethernet/LED_SPD")
			(pinfunction "LED2/PHYAD1")
			(pintype "bidirectional")
		)
		(pad "16" smd oval
			(at -1.25 3.499 270)
			(size 0.3 0.9)
			(layers "F.Cu" "F.Mask" "F.Paste")
			(net 200 "+3V3")
			(pinfunction "DVDDH")
			(pintype "power_in")
		)
		(pad "17" smd oval
			(at -0.75 3.499 270)
			(size 0.3 0.9)
			(layers "F.Cu" "F.Mask" "F.Paste")
			(net 603 "/Ethernet/LED_LINK")
			(pinfunction "LED1/PHAD0/PME_N1")
			(pintype "bidirectional")
		)
		(pad "18" smd oval
			(at -0.25 3.499 270)
			(size 0.3 0.9)
			(layers "F.Cu" "F.Mask" "F.Paste")
			(net 199 "+1V2")
			(pinfunction "DVDDL")
			(pintype "passive")
		)
		(pad "19" smd oval
			(at 0.248 3.499 270)
			(size 0.3 0.9)
			(layers "F.Cu" "F.Mask" "F.Paste")
			(net 733 "/Ethernet/ETH.TXD0")
			(pinfunction "TXD0")
			(pintype "input")
		)
		(pad "20" smd oval
			(at 0.748 3.499 270)
			(size 0.3 0.9)
			(layers "F.Cu" "F.Mask" "F.Paste")
			(net 737 "/Ethernet/ETH.TXD1")
			(pinfunction "TXD1")
			(pintype "input")
		)
		(pad "21" smd oval
			(at 1.249 3.499 270)
			(size 0.3 0.9)
			(layers "F.Cu" "F.Mask" "F.Paste")
			(net 736 "/Ethernet/ETH.TXD2")
			(pinfunction "TXD2")
			(pintype "input")
		)
		(pad "22" smd oval
			(at 1.749 3.499 270)
			(size 0.3 0.9)
			(layers "F.Cu" "F.Mask" "F.Paste")
			(net 735 "/Ethernet/ETH.TXD3")
			(pinfunction "TXD3")
			(pintype "input")
		)
		(pad "23" smd oval
			(at 2.249 3.499 270)
			(size 0.3 0.9)
			(layers "F.Cu" "F.Mask" "F.Paste")
			(net 199 "+1V2")
			(pinfunction "DVDDL")
			(pintype "passive")
		)
		(pad "24" smd oval
			(at 2.749 3.499 270)
			(size 0.3 0.9)
			(layers "F.Cu" "F.Mask" "F.Paste")
			(net 704 "/Ethernet/ETH.TXC")
			(pinfunction "GTX_CLK")
			(pintype "input")
		)
		(pad "25" smd oval
			(at 3.499 2.749)
			(size 0.3 0.9)
			(layers "F.Cu" "F.Mask" "F.Paste")
			(net 732 "/Ethernet/ETH.TX_CTL")
			(pinfunction "TX_EN")
			(pintype "input")
		)
		(pad "26" smd oval
			(at 3.499 2.249)
			(size 0.3 0.9)
			(layers "F.Cu" "F.Mask" "F.Paste")
			(net 199 "+1V2")
			(pinfunction "DVDDL")
			(pintype "passive")
		)
		(pad "27" smd oval
			(at 3.499 1.749)
			(size 0.3 0.9)
			(layers "F.Cu" "F.Mask" "F.Paste")
			(net 676 "/Ethernet/ETH.RXD3")
			(pinfunction "RXD3/MODE3")
			(pintype "input")
		)
		(pad "28" smd oval
			(at 3.499 1.249)
			(size 0.3 0.9)
			(layers "F.Cu" "F.Mask" "F.Paste")
			(net 675 "/Ethernet/ETH.RXD2")
			(pinfunction "RXD2/MODE2")
			(pintype "input")
		)
		(pad "29" smd oval
			(at 3.499 0.748)
			(size 0.3 0.9)
			(layers "F.Cu" "F.Mask" "F.Paste")
			(net 1 "GND")
			(pinfunction "VSS")
			(pintype "power_in")
		)
		(pad "30" smd oval
			(at 3.499 0.248)
			(size 0.3 0.9)
			(layers "F.Cu" "F.Mask" "F.Paste")
			(net 199 "+1V2")
			(pinfunction "DVDDL")
			(pintype "passive")
		)
		(pad "31" smd oval
			(at 3.499 -0.25)
			(size 0.3 0.9)
			(layers "F.Cu" "F.Mask" "F.Paste")
			(net 674 "/Ethernet/ETH.RXD1")
			(pinfunction "RXD1/MODE1")
			(pintype "input")
		)
		(pad "32" smd oval
			(at 3.499 -0.75)
			(size 0.3 0.9)
			(layers "F.Cu" "F.Mask" "F.Paste")
			(net 673 "/Ethernet/ETH.RXD0")
			(pinfunction "RXD0/MODE0")
			(pintype "input")
		)
		(pad "33" smd oval
			(at 3.499 -1.25)
			(size 0.3 0.9)
			(layers "F.Cu" "F.Mask" "F.Paste")
			(net 677 "/Ethernet/ETH.RX_CTL")
			(pinfunction "RX_DV/CLK125_EN")
			(pintype "input")
		)
		(pad "34" smd oval
			(at 3.499 -1.75)
			(size 0.3 0.9)
			(layers "F.Cu" "F.Mask" "F.Paste")
			(net 200 "+3V3")
			(pinfunction "DVDDH")
			(pintype "passive")
		)
		(pad "35" smd oval
			(at 3.499 -2.25)
			(size 0.3 0.9)
			(layers "F.Cu" "F.Mask" "F.Paste")
			(net 678 "/Ethernet/ETH.RXC")
			(pinfunction "RX_CLK/PHYAD2")
			(pintype "input")
		)
		(pad "36" smd oval
			(at 3.499 -2.75)
			(size 0.3 0.9)
			(layers "F.Cu" "F.Mask" "F.Paste")
			(net 705 "/Ethernet/ETH.MDC")
			(pinfunction "MDC")
			(pintype "input")
		)
		(pad "37" smd oval
			(at 2.749 -3.5 270)
			(size 0.3 0.9)
			(layers "F.Cu" "F.Mask" "F.Paste")
			(net 680 "/Ethernet/ETH.MDIO")
			(pinfunction "MDIO")
			(pintype "input")
		)
		(pad "38" smd oval
			(at 2.249 -3.5 270)
			(size 0.3 0.9)
			(layers "F.Cu" "F.Mask" "F.Paste")
			(net 734 "/Ethernet/ETH.~{INT}")
			(pinfunction "~{INT/PME}")
			(pintype "input")
		)
		(pad "39" smd oval
			(at 1.749 -3.5 270)
			(size 0.3 0.9)
			(layers "F.Cu" "F.Mask" "F.Paste")
			(net 199 "+1V2")
			(pinfunction "DVDDL")
			(pintype "passive")
		)
		(pad "40" smd oval
			(at 1.249 -3.5 270)
			(size 0.3 0.9)
			(layers "F.Cu" "F.Mask" "F.Paste")
			(net 200 "+3V3")
			(pinfunction "DVDDH")
			(pintype "passive")
		)
		(pad "41" smd oval
			(at 0.748 -3.5 270)
			(size 0.3 0.9)
			(layers "F.Cu" "F.Mask" "F.Paste")
			(net 679 "/Ethernet/ETH.REF_CLK")
			(pinfunction "CLK125_NDO/LED_MODE")
			(pintype "input")
		)
		(pad "42" smd oval
			(at 0.248 -3.5 270)
			(size 0.3 0.9)
			(layers "F.Cu" "F.Mask" "F.Paste")
			(net 681 "/Ethernet/ETH.~{RESET}")
			(pinfunction "~{RESET}")
			(pintype "input")
		)
		(pad "43" smd oval
			(at -0.25 -3.5 270)
			(size 0.3 0.9)
			(layers "F.Cu" "F.Mask" "F.Paste")
			(net 722 "unconnected-(U15-LDO_O-Pad43)")
			(pinfunction "LDO_O")
			(pintype "input+no_connect")
		)
		(pad "44" smd oval
			(at -0.75 -3.5 270)
			(size 0.3 0.9)
			(layers "F.Cu" "F.Mask" "F.Paste")
			(net 133 "/Ethernet/AVDDL_PLL")
			(pinfunction "AVDDL_PLL")
			(pintype "power_in")
		)
		(pad "45" smd oval
			(at -1.25 -3.5 270)
			(size 0.3 0.9)
			(layers "F.Cu" "F.Mask" "F.Paste")
			(net 300 "Net-(U15-XO)")
			(pinfunction "XO")
			(pintype "input")
		)
		(pad "46" smd oval
			(at -1.75 -3.5 270)
			(size 0.3 0.9)
			(layers "F.Cu" "F.Mask" "F.Paste")
			(net 299 "Net-(U15-XI)")
			(pinfunction "XI")
			(pintype "input")
		)
		(pad "47" smd oval
			(at -2.25 -3.5 270)
			(size 0.3 0.9)
			(layers "F.Cu" "F.Mask" "F.Paste")
			(net 723 "unconnected-(U15-NC-Pad47)")
			(pinfunction "NC")
			(pintype "no_connect")
		)
		(pad "48" smd oval
			(at -2.75 -3.5 270)
			(size 0.3 0.9)
			(layers "F.Cu" "F.Mask" "F.Paste")
			(net 384 "Net-(U15-ISET)")
			(pinfunction "ISET")
			(pintype "output")
		)
		(pad "49" smd rect
			(at 0 0 270)
			(size 3.5 3.5)
			(layers "F.Cu" "F.Mask" "F.Paste")
			(net 1 "GND")
			(pinfunction "PAD_GND")
			(pintype "power_in")
		)
	)
	(footprint "antmicro-footprints:R_0402_1005Metric"
		(layer "F.Cu")
		(at 86.867877 189.779001 180)
		(descr "Resistor SMD 0402")
		(tags "resistor SMD 0402")
		(property "Reference" "R77"
			(at -1.122484 -0.772697 180)
			(layer "F.SilkS")
			(hide yes)
			(effects
				(font
					(size 0.7 0.7)
					(thickness 0.15)
				)
				(justify left bottom)
			)
		)
		(property "Value" "R_0R_0402"
			(at -1.011843 1.772047 180)
			(layer "F.Fab")
			(effects
				(font
					(size 0.7 0.7)
					(thickness 0.15)
				)
				(justify left bottom)
			)
		)
		(property "Datasheet" "https://industrial.panasonic.com/cdbs/www-data/pdf/RDA0000/AOA0000C301.pdf"
			(at 0 0 180)
			(layer "F.Fab")
			(hide yes)
			(effects
				(font
					(size 1.27 1.27)
					(thickness 0.15)
				)
			)
		)
		(property "Author" "Antmicro"
			(at 173.735754 379.558002 0)
			(layer "F.Fab")
			(hide yes)
			(effects
				(font
					(size 1 1)
					(thickness 0.15)
				)
			)
		)
		(property "Current" "1A"
			(at 173.735754 379.558002 0)
			(layer "F.Fab")
			(hide yes)
			(effects
				(font
					(size 1 1)
					(thickness 0.15)
				)
			)
		)
		(property "License" "Apache-2.0"
			(at 173.735754 379.558002 0)
			(layer "F.Fab")
			(hide yes)
			(effects
				(font
					(size 1 1)
					(thickness 0.15)
				)
			)
		)
		(property "MPN" "ERJ2GE0R00X"
			(at 173.735754 379.558002 0)
			(layer "F.Fab")
			(hide yes)
			(effects
				(font
					(size 1 1)
					(thickness 0.15)
				)
			)
		)
		(property "Manufacturer" "Panasonic"
			(at 173.735754 379.558002 0)
			(layer "F.Fab")
			(hide yes)
			(effects
				(font
					(size 1 1)
					(thickness 0.15)
				)
			)
		)
		(property "Tolerance" ""
			(at 173.735754 379.558002 0)
			(layer "F.Fab")
			(hide yes)
			(effects
				(font
					(size 1 1)
					(thickness 0.15)
				)
			)
		)
		(property "Val" "0R"
			(at 173.735754 379.558002 0)
			(layer "F.Fab")
			(hide yes)
			(effects
				(font
					(size 1 1)
					(thickness 0.15)
				)
			)
		)
		(sheetname "/HDMI + SD Card/")
		(sheetfile "hdmi-sd-card.kicad_sch")
		(attr smd)
		(fp_rect
			(start -0.93 -0.47)
			(end 0.93 0.47)
			(stroke
				(width 0.05)
				(type solid)
			)
			(fill no)
			(layer "F.CrtYd")
		)
		(fp_rect
			(start -0.5 -0.25)
			(end 0.5 0.25)
			(stroke
				(width 0.15)
				(type solid)
			)
			(fill no)
			(layer "F.Fab")
		)
		(pad "1" smd roundrect
			(at -0.485 0 180)
			(size 0.59 0.64)
			(layers "F.Cu" "F.Mask" "F.Paste")
			(roundrect_rratio 0.25)
			(net 667 "/FPGA bank 16/HDMI.CLK_N")
			(pintype "passive")
		)
		(pad "2" smd roundrect
			(at 0.485 0 180)
			(size 0.59 0.64)
			(layers "F.Cu" "F.Mask" "F.Paste")
			(roundrect_rratio 0.25)
			(net 349 "/HDMI + SD Card/HDMI_CONN_CLK_N")
			(pintype "passive")
		)
	)
	(footprint "antmicro-footprints:R_0402_1005Metric"
		(layer "F.Cu")
		(at 86.867877 190.779001 180)
		(descr "Resistor SMD 0402")
		(tags "resistor SMD 0402")
		(property "Reference" "R76"
			(at -1.122484 -0.772697 180)
			(layer "F.SilkS")
			(hide yes)
			(effects
				(font
					(size 0.7 0.7)
					(thickness 0.15)
				)
				(justify left bottom)
			)
		)
		(property "Value" "R_0R_0402"
			(at -1.011843 1.772047 180)
			(layer "F.Fab")
			(effects
				(font
					(size 0.7 0.7)
					(thickness 0.15)
				)
				(justify left bottom)
			)
		)
		(property "Datasheet" "https://industrial.panasonic.com/cdbs/www-data/pdf/RDA0000/AOA0000C301.pdf"
			(at 0 0 180)
			(layer "F.Fab")
			(hide yes)
			(effects
				(font
					(size 1.27 1.27)
					(thickness 0.15)
				)
			)
		)
		(property "Author" "Antmicro"
			(at 173.735754 381.558002 0)
			(layer "F.Fab")
			(hide yes)
			(effects
				(font
					(size 1 1)
					(thickness 0.15)
				)
			)
		)
		(property "Current" "1A"
			(at 173.735754 381.558002 0)
			(layer "F.Fab")
			(hide yes)
			(effects
				(font
					(size 1 1)
					(thickness 0.15)
				)
			)
		)
		(property "License" "Apache-2.0"
			(at 173.735754 381.558002 0)
			(layer "F.Fab")
			(hide yes)
			(effects
				(font
					(size 1 1)
					(thickness 0.15)
				)
			)
		)
		(property "MPN" "ERJ2GE0R00X"
			(at 173.735754 381.558002 0)
			(layer "F.Fab")
			(hide yes)
			(effects
				(font
					(size 1 1)
					(thickness 0.15)
				)
			)
		)
		(property "Manufacturer" "Panasonic"
			(at 173.735754 381.558002 0)
			(layer "F.Fab")
			(hide yes)
			(effects
				(font
					(size 1 1)
					(thickness 0.15)
				)
			)
		)
		(property "Tolerance" ""
			(at 173.735754 381.558002 0)
			(layer "F.Fab")
			(hide yes)
			(effects
				(font
					(size 1 1)
					(thickness 0.15)
				)
			)
		)
		(property "Val" "0R"
			(at 173.735754 381.558002 0)
			(layer "F.Fab")
			(hide yes)
			(effects
				(font
					(size 1 1)
					(thickness 0.15)
				)
			)
		)
		(sheetname "/HDMI + SD Card/")
		(sheetfile "hdmi-sd-card.kicad_sch")
		(attr smd)
		(fp_rect
			(start -0.93 -0.47)
			(end 0.93 0.47)
			(stroke
				(width 0.05)
				(type solid)
			)
			(fill no)
			(layer "F.CrtYd")
		)
		(fp_rect
			(start -0.5 -0.25)
			(end 0.5 0.25)
			(stroke
				(width 0.15)
				(type solid)
			)
			(fill no)
			(layer "F.Fab")
		)
		(pad "1" smd roundrect
			(at -0.485 0 180)
			(size 0.59 0.64)
			(layers "F.Cu" "F.Mask" "F.Paste")
			(roundrect_rratio 0.25)
			(net 666 "/FPGA bank 16/HDMI.CLK_P")
			(pintype "passive")
		)
		(pad "2" smd roundrect
			(at 0.485 0 180)
			(size 0.59 0.64)
			(layers "F.Cu" "F.Mask" "F.Paste")
			(roundrect_rratio 0.25)
			(net 348 "/HDMI + SD Card/HDMI_CONN_CLK_P")
			(pintype "passive")
		)
	)
)
